# T6G (Grand Teton) — schematic netlist excerpt (pin names and nets, part order shuffled) for the footprints in the layout excerpt that follows; sources: Cadence DE-HDL packaged netlist, KiCad conversion of 04192023_DAF0TMB3IC0_F0TG_MB_C_brd_V02_OCP.brd

Q72  MOSFET_NCH_DUAL  PJT138K IC  pkg SOT363XD  page 127
  S1  = GND
  G1  = FM_GPU_PWRGD
  D2  = FM_GPU_PWRGD_ISO
  S2  = GND
  G2  = FM_GPU_PWRGD_N
  D1  = FM_GPU_PWRGD_N

C6534  Q_CAP_DIFFBUS  DIFF BUS_0.22UF 6.3V 20% X6S  pkg C0201  page 286 : \1\ = P5E_CPU0_P1_TX_BUF_C_DN<0> ; \2\ = P5E_CPU0_P1_TX_BUF_DN<0>
PC380_2  Q_CAP  22UF 16V 20% X6S  pkg C0805  page 218 : A = SW_P12V_AUX_PVDDCR_CPU1_P1_FLT ; B = GND

(kicad_pcb
	(version 20260206)
	(generator "pcbnew")
	(generator_version "10.0")
	(general
		(thickness 1.6)
		(legacy_teardrops no)
	)
	(paper "A4")
	(title_block
		(title "04192023_DAF0TMB3IC0_F0TG_MB_C_brd_V02_OCP.brd")
		(comment 1 "Grand Teton / footprints 5196-5198 of 8354")
	)
	(layers
		(0 "F.Cu" signal "TOP")
		(4 "In1.Cu" signal "GND")
		(6 "In2.Cu" signal "IN1")
		(8 "In3.Cu" signal "GND1")
		(10 "In4.Cu" signal "IN2")
		(12 "In5.Cu" signal "GND2")
		(14 "In6.Cu" signal "IN3")
		(16 "In7.Cu" signal "GND3")
		(18 "In8.Cu" signal "VCC")
		(20 "In9.Cu" signal "VCC1")
		(22 "In10.Cu" signal "GND4")
		(24 "In11.Cu" signal "IN4")
		(26 "In12.Cu" signal "GND5")
		(28 "In13.Cu" signal "IN5")
		(30 "In14.Cu" signal "GND6")
		(32 "In15.Cu" signal "IN6")
		(34 "In16.Cu" signal "GND7")
		(2 "B.Cu" signal "BOTTOM")
		(9 "F.Adhes" user "F.Adhesive")
		(11 "B.Adhes" user "B.Adhesive")
		(13 "F.Paste" user "Package Geometry/Pastemask Top")
		(15 "B.Paste" user "Package Geometry/Pastemask Bottom")
		(5 "F.SilkS" user "Ref Des/Silkscreen Top")
		(7 "B.SilkS" user "Ref Des/Silkscreen Bottom")
		(1 "F.Mask" user "Board Geometry/Soldermask Top")
		(3 "B.Mask" user "Board Geometry/Soldermask Bottom")
		(17 "Dwgs.User" user "User.Drawings")
		(19 "Cmts.User" user "User.Comments")
		(21 "Eco1.User" user "User.Eco1")
		(23 "Eco2.User" user "User.Eco2")
		(25 "Edge.Cuts" user "Board Geometry/Outline")
		(27 "Margin" user)
		(31 "F.CrtYd" user "Package Geometry/Place Bound Top")
		(29 "B.CrtYd" user "Package Geometry/Place Bound Bottom")
		(35 "F.Fab" user "Ref Des/Assembly Top")
		(33 "B.Fab" user "Ref Des/Assembly Bottom")
	)
	(footprint ""
		(layer "B.Cu")
		(at 48.618902 -425.275248)
		(property "Reference" "Q72"
			(at 0.318008 -1.866138 0)
			(unlocked yes)
			(layer "B.SilkS")
			(effects
				(font
					(size 0.7874 0.5842)
					(thickness 0.1524)
				)
				(justify left mirror)
			)
		)
		(property "Value" ""
			(at 0 0 0)
			(layer "B.Fab")
			(effects
				(font
					(size 1.27 1.27)
				)
				(justify mirror)
			)
		)
		(duplicate_pad_numbers_are_jumpers no)
		(fp_line
			(start -1.332738 -1.100074)
			(end -1.332738 1.100074)
			(stroke
				(width 0.1524)
				(type default)
			)
			(layer "B.SilkS")
		)
		(fp_line
			(start -1.332738 1.100074)
			(end 1.332738 1.100074)
			(stroke
				(width 0.1524)
				(type default)
			)
			(layer "B.SilkS")
		)
		(fp_line
			(start -0.4826 -1.100074)
			(end -1.332738 -1.100074)
			(stroke
				(width 0.1524)
				(type default)
			)
			(layer "B.SilkS")
		)
		(fp_line
			(start 0 -0.541274)
			(end -0.4826 -1.100074)
			(stroke
				(width 0.1524)
				(type default)
			)
			(layer "B.SilkS")
		)
		(fp_line
			(start 0.4826 -1.100074)
			(end 0 -0.541274)
			(stroke
				(width 0.1524)
				(type default)
			)
			(layer "B.SilkS")
		)
		(fp_line
			(start 1.332738 -1.100074)
			(end 0.4826 -1.100074)
			(stroke
				(width 0.1524)
				(type default)
			)
			(layer "B.SilkS")
		)
		(fp_line
			(start 1.332738 1.100074)
			(end 1.332738 -1.100074)
			(stroke
				(width 0.1524)
				(type default)
			)
			(layer "B.SilkS")
		)
		(fp_poly
			(pts
				(xy 1.62814 -1.297686) (xy 2.372614 -1.545844) (xy 1.876298 -2.042414)
			)
			(stroke
				(width 0)
				(type default)
			)
			(fill yes)
			(layer "B.SilkS")
		)
		(fp_line
			(start -0.674878 -1.100074)
			(end -0.674878 1.100074)
			(stroke
				(width 0.1)
				(type default)
			)
			(layer "B.Fab")
		)
		(fp_line
			(start -0.674878 1.100074)
			(end 0.674878 1.100074)
			(stroke
				(width 0.1)
				(type default)
			)
			(layer "B.Fab")
		)
		(fp_line
			(start 0.674878 -1.100074)
			(end -0.674878 -1.100074)
			(stroke
				(width 0.1)
				(type default)
			)
			(layer "B.Fab")
		)
		(fp_line
			(start 0.674878 1.100074)
			(end 0.674878 -1.100074)
			(stroke
				(width 0.1)
				(type default)
			)
			(layer "B.Fab")
		)
		(fp_poly
			(pts
				(xy 2.2352 -0.298958) (xy 2.2352 -1.001014) (xy 1.533144 -0.649986)
			)
			(stroke
				(width 0)
				(type default)
			)
			(fill yes)
			(layer "B.Fab")
		)
		(pad "1" smd rect
			(at 0.94996 -0.649986 90)
			(size 0.4318 0.508)
			(layers "B.Cu" "B.Mask" "B.Paste")
			(net "GND")
		)
		(pad "2" smd rect
			(at 0.94996 0 90)
			(size 0.4318 0.508)
			(layers "B.Cu" "B.Mask" "B.Paste")
			(net "FM_GPU_PWRGD")
		)
		(pad "3" smd rect
			(at 0.94996 0.649986 90)
			(size 0.4318 0.508)
			(layers "B.Cu" "B.Mask" "B.Paste")
			(net "FM_GPU_PWRGD_ISO")
		)
		(pad "4" smd rect
			(at -0.94996 0.649986 90)
			(size 0.4318 0.508)
			(layers "B.Cu" "B.Mask" "B.Paste")
			(net "GND")
		)
		(pad "5" smd rect
			(at -0.94996 0 90)
			(size 0.4318 0.508)
			(layers "B.Cu" "B.Mask" "B.Paste")
			(net "FM_GPU_PWRGD_N")
		)
		(pad "6" smd rect
			(at -0.94996 -0.649986 90)
			(size 0.4318 0.508)
			(layers "B.Cu" "B.Mask" "B.Paste")
			(net "FM_GPU_PWRGD_N")
		)
	)
	(footprint ""
		(layer "B.Cu")
		(at 305.300126 -416.899344 90)
		(property "Reference" "C6534"
			(at 0 0 90)
			(layer "B.SilkS")
			(hide yes)
			(effects
				(font
					(size 1.27 1.27)
				)
				(justify mirror)
			)
		)
		(property "Value" ""
			(at 0 0 90)
			(layer "B.Fab")
			(effects
				(font
					(size 1.27 1.27)
				)
				(justify mirror)
			)
		)
		(duplicate_pad_numbers_are_jumpers no)
		(fp_line
			(start 0.299974 -0.150114)
			(end -0.299974 -0.150114)
			(stroke
				(width 0.1)
				(type default)
			)
			(layer "B.Fab")
		)
		(fp_line
			(start -0.299974 -0.150114)
			(end -0.299974 0.150114)
			(stroke
				(width 0.1)
				(type default)
			)
			(layer "B.Fab")
		)
		(fp_line
			(start 0.299974 0.150114)
			(end 0.299974 -0.150114)
			(stroke
				(width 0.1)
				(type default)
			)
			(layer "B.Fab")
		)
		(fp_line
			(start -0.299974 0.150114)
			(end 0.299974 0.150114)
			(stroke
				(width 0.1)
				(type default)
			)
			(layer "B.Fab")
		)
		(pad "1" smd rect
			(at 0.2667 0 270)
			(size 0.3048 0.381)
			(layers "B.Cu" "B.Mask" "B.Paste")
			(net "P5E_CPU0_P1_TX_BUF_C_DN<0>")
		)
		(pad "2" smd rect
			(at -0.2667 0 270)
			(size 0.3048 0.381)
			(layers "B.Cu" "B.Mask" "B.Paste")
			(net "P5E_CPU0_P1_TX_BUF_DN<0>")
		)
	)
	(footprint ""
		(layer "B.Cu")
		(at 82.014314 -335.060798 90)
		(property "Reference" "PC380_2"
			(at 0 0 90)
			(layer "B.SilkS")
			(hide yes)
			(effects
				(font
					(size 1.27 1.27)
				)
				(justify mirror)
			)
		)
		(property "Value" ""
			(at 0 0 90)
			(layer "B.Fab")
			(effects
				(font
					(size 1.27 1.27)
				)
				(justify mirror)
			)
		)
		(duplicate_pad_numbers_are_jumpers no)
		(fp_line
			(start 1.524 -0.762)
			(end -1.524 -0.762)
			(stroke
				(width 0.1524)
				(type default)
			)
			(layer "B.SilkS")
		)
		(fp_line
			(start -1.524 -0.762)
			(end -1.524 0.762)
			(stroke
				(width 0.1524)
				(type default)
			)
			(layer "B.SilkS")
		)
		(fp_line
			(start 1.524 0.762)
			(end 1.524 -0.762)
			(stroke
				(width 0.1524)
				(type default)
			)
			(layer "B.SilkS")
		)
		(fp_line
			(start -1.524 0.762)
			(end 1.524 0.762)
			(stroke
				(width 0.1524)
				(type default)
			)
			(layer "B.SilkS")
		)
		(fp_line
			(start 1.1049 -0.724916)
			(end 1.1049 0.724916)
			(stroke
				(width 0.1)
				(type default)
			)
			(layer "B.Fab")
		)
		(fp_line
			(start -1.1049 -0.724916)
			(end 1.1049 -0.724916)
			(stroke
				(width 0.1)
				(type default)
			)
			(layer "B.Fab")
		)
		(fp_line
			(start 1.1049 0.724916)
			(end -1.1049 0.724916)
			(stroke
				(width 0.1)
				(type default)
			)
			(layer "B.Fab")
		)
		(fp_line
			(start -1.1049 0.724916)
			(end -1.1049 -0.724916)
			(stroke
				(width 0.1)
				(type default)
			)
			(layer "B.Fab")
		)
		(pad "1" smd rect
			(at 0.889 0 90)
			(size 1.016 1.27)
			(layers "B.Cu" "B.Mask" "B.Paste")
			(net "SW_P12V_AUX_PVDDCR_CPU1_P1_FLT")
		)
		(pad "2" smd rect
			(at -0.889 0 90)
			(size 1.016 1.27)
			(layers "B.Cu" "B.Mask" "B.Paste")
			(net "GND")
		)
	)
)
